# S9S_MB_2U (Grand Teton) — schematic netlist excerpt (pin names and nets, part order shuffled) for the footprints in the layout excerpt that follows; sources: Cadence DE-HDL packaged netlist, KiCad conversion of 03242023_DA0F0TMBIJ0_F0T_Motherboard_J_brd_V01_OCP.brd

R4114  Q_RES  10K 1% CHIP  pkg 0402LF  page 184 : A = PD_PCH_GPP_E_10 ; B = GND
C119  Q_CAP  0.047UF 25V 10% X7R  pkg C0402  page 210 : A = P3V3_AUX_CLK_GEN_VDDMXCK_CK440 ; B = GND

(kicad_pcb
	(version 20260206)
	(generator "pcbnew")
	(generator_version "10.0")
	(general
		(thickness 1.6)
		(legacy_teardrops no)
	)
	(paper "A4")
	(title_block
		(title "03242023_DA0F0TMBIJ0_F0T_Motherboard_J_brd_V01_OCP.brd")
		(comment 1 "Grand Teton / footprints 4241-4242 of 6105")
	)
	(layers
		(0 "F.Cu" signal "TOP")
		(4 "In1.Cu" signal "GND")
		(6 "In2.Cu" signal "IN1")
		(8 "In3.Cu" signal "GND1")
		(10 "In4.Cu" signal "IN2")
		(12 "In5.Cu" signal "GND2")
		(14 "In6.Cu" signal "IN3")
		(16 "In7.Cu" signal "GND3")
		(18 "In8.Cu" signal "VCC")
		(20 "In9.Cu" signal "VCC1")
		(22 "In10.Cu" signal "GND4")
		(24 "In11.Cu" signal "IN4")
		(26 "In12.Cu" signal "GND5")
		(28 "In13.Cu" signal "IN5")
		(30 "In14.Cu" signal "GND6")
		(32 "In15.Cu" signal "IN6")
		(34 "In16.Cu" signal "GND7")
		(2 "B.Cu" signal "BOTTOM")
		(9 "F.Adhes" user "F.Adhesive")
		(11 "B.Adhes" user "B.Adhesive")
		(13 "F.Paste" user "Package Geometry/Pastemask Top")
		(15 "B.Paste" user "Package Geometry/Pastemask Bottom")
		(5 "F.SilkS" user "Ref Des/Silkscreen Top")
		(7 "B.SilkS" user "Ref Des/Silkscreen Bottom")
		(1 "F.Mask" user "Board Geometry/Soldermask Top")
		(3 "B.Mask" user "Board Geometry/Soldermask Bottom")
		(17 "Dwgs.User" user "User.Drawings")
		(19 "Cmts.User" user "User.Comments")
		(21 "Eco1.User" user "User.Eco1")
		(23 "Eco2.User" user "User.Eco2")
		(25 "Edge.Cuts" user "Board Geometry/Outline")
		(27 "Margin" user)
		(31 "F.CrtYd" user "Package Geometry/Place Bound Top")
		(29 "B.CrtYd" user "Package Geometry/Place Bound Bottom")
		(35 "F.Fab" user "Ref Des/Assembly Top")
		(33 "B.Fab" user "Ref Des/Assembly Bottom")
	)
	(footprint ""
		(layer "B.Cu")
		(at 257.32867 -102.28834 90)
		(property "Reference" "C119"
			(at 0 0 90)
			(layer "B.SilkS")
			(hide yes)
			(effects
				(font
					(size 1.27 1.27)
				)
				(justify mirror)
			)
		)
		(property "Value" ""
			(at 0 0 90)
			(layer "B.Fab")
			(effects
				(font
					(size 1.27 1.27)
				)
				(justify mirror)
			)
		)
		(duplicate_pad_numbers_are_jumpers no)
		(fp_line
			(start 0.7874 -0.4064)
			(end -0.7874 -0.4064)
			(stroke
				(width 0.1524)
				(type default)
			)
			(layer "B.SilkS")
		)
		(fp_line
			(start -0.7874 -0.4064)
			(end -0.7874 0.4064)
			(stroke
				(width 0.1524)
				(type default)
			)
			(layer "B.SilkS")
		)
		(fp_line
			(start 0.7874 0.4064)
			(end 0.7874 -0.4064)
			(stroke
				(width 0.1524)
				(type default)
			)
			(layer "B.SilkS")
		)
		(fp_line
			(start -0.7874 0.4064)
			(end 0.7874 0.4064)
			(stroke
				(width 0.1524)
				(type default)
			)
			(layer "B.SilkS")
		)
		(fp_line
			(start 0.67945 -0.305054)
			(end 0.12065 -0.305054)
			(stroke
				(width 0.1)
				(type default)
			)
			(layer "B.Fab")
		)
		(fp_line
			(start 0.12065 -0.305054)
			(end 0.12065 -0.2794)
			(stroke
				(width 0.1)
				(type default)
			)
			(layer "B.Fab")
		)
		(fp_line
			(start -0.12065 -0.3048)
			(end -0.67945 -0.3048)
			(stroke
				(width 0.1)
				(type default)
			)
			(layer "B.Fab")
		)
		(fp_line
			(start -0.67945 -0.3048)
			(end -0.67945 0.3048)
			(stroke
				(width 0.1)
				(type default)
			)
			(layer "B.Fab")
		)
		(fp_line
			(start 0.12065 -0.2794)
			(end -0.12065 -0.2794)
			(stroke
				(width 0.1)
				(type default)
			)
			(layer "B.Fab")
		)
		(fp_line
			(start -0.12065 -0.2794)
			(end -0.12065 -0.3048)
			(stroke
				(width 0.1)
				(type default)
			)
			(layer "B.Fab")
		)
		(fp_line
			(start 0.12065 0.2794)
			(end 0.12065 0.3048)
			(stroke
				(width 0.1)
				(type default)
			)
			(layer "B.Fab")
		)
		(fp_line
			(start -0.120396 0.2794)
			(end 0.12065 0.2794)
			(stroke
				(width 0.1)
				(type default)
			)
			(layer "B.Fab")
		)
		(fp_line
			(start 0.67945 0.3048)
			(end 0.67945 -0.305054)
			(stroke
				(width 0.1)
				(type default)
			)
			(layer "B.Fab")
		)
		(fp_line
			(start 0.12065 0.3048)
			(end 0.67945 0.3048)
			(stroke
				(width 0.1)
				(type default)
			)
			(layer "B.Fab")
		)
		(fp_line
			(start -0.120396 0.3048)
			(end -0.120396 0.2794)
			(stroke
				(width 0.1)
				(type default)
			)
			(layer "B.Fab")
		)
		(fp_line
			(start -0.67945 0.3048)
			(end -0.120396 0.3048)
			(stroke
				(width 0.1)
				(type default)
			)
			(layer "B.Fab")
		)
		(pad "1" smd circle
			(at 0.40005 0 270)
			(size 0 0)
			(layers "B.Cu" "B.Mask" "B.Paste")
			(net "P3V3_AUX_CLK_GEN_VDDMXCK_CK440")
		)
		(pad "2" smd circle
			(at -0.40005 0 270)
			(size 0 0)
			(layers "B.Cu" "B.Mask" "B.Paste")
			(net "GND")
		)
	)
	(footprint ""
		(layer "B.Cu")
		(at 369.49888 -46.192948 180)
		(property "Reference" "R4114"
			(at 0 0 0)
			(layer "B.SilkS")
			(hide yes)
			(effects
				(font
					(size 1.27 1.27)
				)
				(justify mirror)
			)
		)
		(property "Value" ""
			(at 0 0 0)
			(layer "B.Fab")
			(effects
				(font
					(size 1.27 1.27)
				)
				(justify mirror)
			)
		)
		(duplicate_pad_numbers_are_jumpers no)
		(fp_line
			(start 0.7874 0.4064)
			(end 0.7874 -0.4064)
			(stroke
				(width 0.1524)
				(type default)
			)
			(layer "B.SilkS")
		)
		(fp_line
			(start 0.7874 -0.4064)
			(end -0.7874 -0.4064)
			(stroke
				(width 0.1524)
				(type default)
			)
			(layer "B.SilkS")
		)
		(fp_line
			(start -0.7874 0.4064)
			(end 0.7874 0.4064)
			(stroke
				(width 0.1524)
				(type default)
			)
			(layer "B.SilkS")
		)
		(fp_line
			(start -0.7874 -0.4064)
			(end -0.7874 0.4064)
			(stroke
				(width 0.1524)
				(type default)
			)
			(layer "B.SilkS")
		)
		(fp_line
			(start 0.67945 0.3048)
			(end 0.67945 -0.305054)
			(stroke
				(width 0.1)
				(type default)
			)
			(layer "B.Fab")
		)
		(fp_line
			(start 0.67945 -0.305054)
			(end 0.12065 -0.305054)
			(stroke
				(width 0.1)
				(type default)
			)
			(layer "B.Fab")
		)
		(fp_line
			(start 0.12065 0.3048)
			(end 0.67945 0.3048)
			(stroke
				(width 0.1)
				(type default)
			)
			(layer "B.Fab")
		)
		(fp_line
			(start 0.12065 0.2794)
			(end 0.12065 0.3048)
			(stroke
				(width 0.1)
				(type default)
			)
			(layer "B.Fab")
		)
		(fp_line
			(start 0.12065 -0.2794)
			(end -0.12065 -0.2794)
			(stroke
				(width 0.1)
				(type default)
			)
			(layer "B.Fab")
		)
		(fp_line
			(start 0.12065 -0.305054)
			(end 0.12065 -0.2794)
			(stroke
				(width 0.1)
				(type default)
			)
			(layer "B.Fab")
		)
		(fp_line
			(start -0.120396 0.3048)
			(end -0.120396 0.2794)
			(stroke
				(width 0.1)
				(type default)
			)
			(layer "B.Fab")
		)
		(fp_line
			(start -0.120396 0.2794)
			(end 0.12065 0.2794)
			(stroke
				(width 0.1)
				(type default)
			)
			(layer "B.Fab")
		)
		(fp_line
			(start -0.12065 -0.2794)
			(end -0.12065 -0.3048)
			(stroke
				(width 0.1)
				(type default)
			)
			(layer "B.Fab")
		)
		(fp_line
			(start -0.12065 -0.3048)
			(end -0.67945 -0.3048)
			(stroke
				(width 0.1)
				(type default)
			)
			(layer "B.Fab")
		)
		(fp_line
			(start -0.67945 0.3048)
			(end -0.120396 0.3048)
			(stroke
				(width 0.1)
				(type default)
			)
			(layer "B.Fab")
		)
		(fp_line
			(start -0.67945 -0.3048)
			(end -0.67945 0.3048)
			(stroke
				(width 0.1)
				(type default)
			)
			(layer "B.Fab")
		)
		(pad "1" smd circle
			(at 0.40005 0)
			(size 0 0)
			(layers "B.Cu" "B.Mask" "B.Paste")
			(net "PD_PCH_GPP_E_10")
		)
		(pad "2" smd circle
			(at -0.40005 0)
			(size 0 0)
			(layers "B.Cu" "B.Mask" "B.Paste")
			(net "GND")
		)
	)
)
